FILE_TYPE = CONNECTIVITY;
{Allegro Design Entry HDL 16.6-p007 (v16-6-112F) 10/10/2012}
"PAGE_NUMBER" = 249;
0"NC";
1"GND\g";
2"GND\g";
3"GND\g";
4"P3V3_STBY\g";
5"GND\g";
6"P3V3_STBY\g";
7"GND\g";
8"P5V_STBY\g";
9"GND\g";
10"GND\g";
11"P3V3_STBY\g";
12"FM_TPM_PRES_RST_N";
13"VREF_2V2";
14"FM_TPM_PRES_RST";
15"RST_BMC_EXTRST_N";
16"FM_TPM_PRES_RST_N_R";
17"BMC_TPM_HW_C_RST";
18"BMC_SELF_HW_D_RST";
19"BMC_SELF_HW_RST";
20"FM_TPM_PRES_N";
%"GND"
"1","(-3200,3600)","0","mstr_symbols","I10";
;
VOLTAGE"0.0V"
BODY_TYPE"PLUMBING"
CDS_LIB"mstr_symbols"
SIZE"1B"
HDL_POWER"GND";
"A\NAC"1;
%"GND"
"1","(-4850,1675)","0","mstr_symbols","I11";
;
CDS_LIB"mstr_symbols"
HDL_POWER"GND"
SIZE"1B"
BODY_TYPE"PLUMBING"
VOLTAGE"0.0V";
"A\NAC"2;
%"GND"
"1","(-2350,2150)","0","mstr_symbols","I14";
;
VOLTAGE"0.0V"
BODY_TYPE"PLUMBING"
CDS_LIB"mstr_symbols"
SIZE"1B"
HDL_POWER"GND";
"A\NAC"3;
%"LMV331IDCKRG4-GP"
"1","(-2300,2550)","0","w_hdl","I15";
;
CDS_SEC"1"
$SEC"1"
CDS_LOCATION"Q9W4"
VALUE"LMV331IDCKRG4-GP"
LOCATION"Q9W4"
CDS_LMAN_SYM_OUTLINE"-100,100,100,-100"
CDS_LIB"w_hdl"
PART_NUMBER"74.00331.A2F"
PACK_TYPE"DISCRET-G";
"GND"
$PN"2"3;
"VCC"
$PN"5"8;
"OUT"
$PN"4"20;
"-IN"
$PN"3"13;
"+IN"
$PN"1"12;
%"P3V3_STBY"
"1","(-4850,3050)","0","mstr_symbols","I16";
;
CDS_LIB"mstr_symbols"
SIZE"1B"
BODY_TYPE"PLUMBING"
HDL_POWER"P3V3_STBY"
VOLTAGE"3.3V";
"G\NAC"4;
%"RES"
"2","(-6850,1950)","0","mstr_discrete","I2";
;
CDS_SEC"1"
CDS_LOCATION"R3W1"
PACK_TYPE"0402"
LOCATION"R3W1"
MATERIAL"CHIP"
TOLERANCE"1%"
WATTAGE"1/16W"
NEW_VALUE"470K"
CONFIG"64.47035.L0L"
VALUE"1.00K"
PART_NUMBER"G21796-026"
SEC"1"
SEC_TYPE"0402"
ROOM"BMC_DEBUG_HEADER"
CDS_LIB"mstr_discrete";
"A"
$PN"1"18;
"B"
$PN"2"7;
%"GND"
"1","(-2050,2800)","0","mstr_symbols","I20";
;
CDS_LIB"mstr_symbols"
HDL_POWER"GND"
SIZE"1B"
BODY_TYPE"PLUMBING"
VOLTAGE"0.0V";
"A\NAC"5;
%"P3V3_STBY"
"1","(-3200,4800)","0","mstr_symbols","I24";
;
VOLTAGE"3.3V"
CDS_LIB"mstr_symbols"
SIZE"1B"
BODY_TYPE"PLUMBING"
HDL_POWER"P3V3_STBY";
"G\NAC"6;
%"NPN"
"1","(-3250,3850)","0","mstr_discrete","I29";
;
CDS_SEC"1"
CDS_LOCATION"Q9W2"
VALUE"MMBT3904"
MATERIAL"IC"
LOCATION"Q9W2"
PACK_TYPE"SM"
PART_NUMBER"C52245-001"
CDS_LIB"mstr_discrete"
ROOM"SB"
SEC_TYPE"SM"
SEC"1";
"C"
$PN"3"14;
"E"
$PN"2"1;
"B"
$PN"1"16;
%"GND"
"1","(-6850,1700)","0","mstr_symbols","I3";
;
VOLTAGE"0.0V"
BODY_TYPE"PLUMBING"
CDS_LIB"mstr_symbols"
SIZE"1B"
HDL_POWER"GND";
"A\NAC"7;
%"FET_N"
"8","(-4850,2250)","0","mstr_discrete","I30";
;
CDS_SEC"1"
CDS_LOCATION"Q9W1"
PART_NUMBER"C79254-001"
LOCATION"Q9W1"
VALUE"2N7002"
MATERIAL"FET"
PACK_TYPE"SOT23LF"
SEC"1"
SEC_TYPE"SOT23LF"
CDS_LIB"mstr_discrete"
ROOM"HOT_SWAP";
"GATE"
$PN"1"17;
"DRN"
$PN"3"12;
"SRC"
$PN"2"2;
%"47KR2F-GP"
"1","(-4325,3850)","1","w_hdl","I31";
;
CDS_SEC"1"
$SEC"1"
CDS_LOCATION"R3W4"
VALUE"47KR2F-GP"
ATTRIBUTE"47KOHM"
RATED"1/16W"
TOLERANCE"1%"
LOCATION"R3W4"
PACK_SIZE"0402"
CDS_LMAN_SYM_OUTLINE"-50,75,50,-75"
CDS_LIB"w_hdl"
PART_NUMBER"64.47025.6DL"
PACK_TYPE"RCL_GP";
"2"
$PN"2"16;
"1"
$PN"1"12;
%"RES"
"1","(-6150,3350)","0","mstr_discrete","I34";
;
CDS_SEC"1"
CDS_LOCATION"R8W1"
LOCATION"R8W1"
PART_NUMBER"G21497-005"
TOLERANCE"5%"
PACK_TYPE"0402"
POP"NOPOP"
VALUE"0.0"
WATTAGE"1/16W"
MATERIAL"CHIP"
CDS_LIB"mstr_discrete"
ROOM"PVCCIN_CPU0_VR"
SEC"1"
SEC_TYPE"0402";
"B"
$PN"2"12;
"A"
$PN"1"18;
%"P5V_STBY"
"1","(-2050,3250)","0","mstr_symbols","I35";
;
CDS_LIB"mstr_symbols"
HDL_POWER"P5V_STBY"
BODY_TYPE"PLUMBING"
VOLTAGE"5.0V"
SIZE"1B";
"G\NAC"8;
%"RES"
"2","(-4850,2850)","0","mstr_discrete","I36";
;
CDS_SEC"1"
CDS_LOCATION"R3W3"
MATERIAL"EMPTY"
WATTAGE"1/16W"
LOCATION"R3W3"
VALUE"10.0K"
TOLERANCE"1%"
PART_NUMBER"G21796-016"
PACK_TYPE"0402"
SEC"1"
SEC_TYPE"0402"
CDS_LIB"mstr_discrete"
ROOM"DB1200ZL"
BOM_COST"SYS_CLOCK";
"A"
$PN"1"4;
"B"
$PN"2"12;
%"CAP_A"
"1","(-2050,3000)","0","dev_discrete","I37";
;
PART_NUMBER"A36096-030"
TOLERANCE"10%"
LOCATION"C8W2"
VALUE"0.1UF"
VOLTAGE"16V"
MATERIAL"X7R"
PACK_TYPE"0402V"
SEC"1"
SEC_TYPE"0402V"
ROOM"VDDQ_KLM_PWR_VR"
CDS_SEC"1"
CDS_LIB"dev_discrete"
CDS_LOCATION"C8W2";
"B"
$PN"2"5;
"A"
$PN"1"8;
%"RES"
"2","(-2300,4450)","2","mstr_discrete","I48";
;
WATTAGE"1/16W"
TOLERANCE"1%"
MATERIAL"CHIP"
LOCATION"R3W6"
PACK_TYPE"0402"
PART_NUMBER"G21796-072"
VALUE"4.75K"
CDS_SEC"1"
CDS_LOCATION"R3W6"
NO_XNET_CONNECTION"1"
BOM_COST"MIO_BIOS_MEM"
ROOM"SB_SPI"
CDS_LIB"mstr_discrete"
SEC_TYPE"0402"
SEC"1";
"A"
$PN"1"6;
"B"
$PN"2"15;
%"NPN"
"1","(-2350,4100)","0","mstr_discrete","I49";
;
MATERIAL"IC"
LOCATION"Q9W3"
VALUE"MMBT3904"
PART_NUMBER"C52245-001"
PACK_TYPE"SM"
CDS_SEC"1"
CDS_LOCATION"Q9W3"
ROOM"SB"
CDS_LIB"mstr_discrete"
SEC_TYPE"SM"
SEC"1";
"C"
$PN"3"15;
"E"
$PN"2"9;
"B"
$PN"1"14;
%"GND"
"1","(-2300,3850)","0","mstr_symbols","I50";
;
CDS_LIB"mstr_symbols"
SIZE"1B"
HDL_POWER"GND"
BODY_TYPE"PLUMBING"
VOLTAGE"0.0V";
"A\NAC"9;
%"SC1U16V3KX-2GP"
"1","(-6625,2150)","1","w_hdl","I52";
;
PACK_SIZE"0603"
RATED"16V"
LOCATION"C8W1"
TYPE"X5R"
ATTRIBUTE"1UF"
VALUE"SC1U16V3KX-2GP"
TOLERANCE"10%"
CDS_LIB"w_hdl"
CDS_LMAN_SYM_OUTLINE"-50,25,50,-25"
PART_NUMBER"78.10521.5BL"
PACK_TYPE"SMD-BCG"
$SEC"1"
CDS_SEC"1"
CDS_LOCATION"C8W1";
"2"
$PN"2"17;
"1"
$PN"1"18;
%"DIODE"
"1","(-7050,2150)","6","mstr_discrete","I55";
;
CDS_SEC"1"
PACK_TYPE"SMLF"
MATERIAL"IC"
VALUE"BAT54WS"
PART_NUMBER"C73510-001"
LOCATION"CR3W1"
CDS_LIB"mstr_discrete"
SEC_TYPE"SMLF"
SEC"1"
CDS_LOCATION"CR3W1";
"C"
$PN"1"18;
"A"
$PN"2"19;
%"RES"
"2","(-6350,1950)","0","mstr_discrete","I56";
;
TOLERANCE"1%"
PACK_TYPE"0402"
PART_NUMBER"G21796-010"
MATERIAL"CHIP"
WATTAGE"1/16W"
VALUE"100.0K"
LOCATION"R3W2"
CDS_SEC"1"
ROOM"SB"
$SEC"1"
CDS_LIB"mstr_discrete"
CDS_LOCATION"R3W2";
"A"
$PN"1"17;
"B"
$PN"2"2;
%"CAP_A"
"1","(-5950,1950)","0","dev_discrete","I57";
;
PART_NUMBER"A36096-030"
MATERIAL"X7R"
PACK_TYPE"0402V"
LOCATION"C3W2"
VALUE"0.1UF"
VOLTAGE"16V"
TOLERANCE"10%"
SEC"1"
SEC_TYPE"0402V"
CDS_SEC"1"
CDS_LIB"dev_discrete"
BOM_COST"PROC_SIDEBAND"
ROOM"PROC_SIDEBAND"
CDS_LOCATION"C3W2";
"B"
$PN"2"2;
"A"
$PN"1"17;
%"RES"
"2","(-3200,4350)","0","mstr_discrete","I58";
;
CDS_SEC"1"
LOCATION"R3W5"
VALUE"10.0K"
TOLERANCE"1%"
PART_NUMBER"G21796-016"
WATTAGE"1/16W"
PACK_TYPE"0402"
MATERIAL"CHIP"
ROOM"CPU0"
BOM_COST"PROC_SIDEBAND"
CDS_LIB"mstr_discrete"
SEC_TYPE"0402"
SEC"1"
CDS_LOCATION"R3W5";
"A"
$PN"1"6;
"B"
$PN"2"14;
%"GND"
"1","(-3325,1975)","0","mstr_symbols","I6";
;
CDS_LIB"mstr_symbols"
HDL_POWER"GND"
SIZE"1B"
BODY_TYPE"PLUMBING"
VOLTAGE"0.0V";
"A\NAC"10;
%"RES"
"2","(-3325,2300)","0","mstr_discrete","I7";
;
CDS_SEC"1"
CDS_LOCATION"R3W9"
VALUE"10.0K"
LOCATION"R3W9"
TOLERANCE"1%"
PACK_TYPE"0402"
WATTAGE"1/16W"
PART_NUMBER"G21796-016"
MATERIAL"CHIP"
CDS_LIB"mstr_discrete"
BOM_COST"ST_FLASH"
ROOM"M_2"
SEC"1"
SEC_TYPE"0402";
"A"
$PN"1"13;
"B"
$PN"2"10;
%"RES"
"2","(-3325,2775)","2","mstr_discrete","I8";
;
CDS_SEC"1"
CDS_LOCATION"R3W7"
PART_NUMBER"G21796-072"
WATTAGE"1/16W"
LOCATION"R3W7"
TOLERANCE"1%"
MATERIAL"CHIP"
VALUE"4.75K"
PACK_TYPE"0402"
ROOM"SB_SPI"
BOM_COST"MIO_BIOS_MEM"
NO_XNET_CONNECTION"1"
CDS_LIB"mstr_discrete"
SEC"1"
SEC_TYPE"0402";
"A"
$PN"1"11;
"B"
$PN"2"13;
%"P3V3_STBY"
"1","(-3325,3100)","0","mstr_symbols","I9";
;
HDL_POWER"P3V3_STBY"
BODY_TYPE"PLUMBING"
SIZE"1B"
CDS_LIB"mstr_symbols"
VOLTAGE"3.3V";
"G\NAC"11;
END.
